# T6G (Grand Teton) — schematic netlist excerpt (pin names and nets, part order shuffled) for the footprints in the layout excerpt that follows; sources: Cadence DE-HDL packaged netlist, KiCad conversion of 04192023_DAF0TMB3IC0_F0TG_MB_C_brd_V02_OCP.brd

R3465  Q_RES  10K 1% CHIP  pkg 0402LF  page 126 : A = P3V3_AUX ; B = GPU_HMC_PRSNT_N
R6015  Q_RES  0 5% CHIP  pkg 0402LF  page 150 : A = SGPIO_SCM_LD_<1> ; B = SGPIO_SCM_LD_R_<1>

(kicad_pcb
	(version 20260206)
	(generator "pcbnew")
	(generator_version "10.0")
	(general
		(thickness 1.6)
		(legacy_teardrops no)
	)
	(paper "A4")
	(title_block
		(title "04192023_DAF0TMB3IC0_F0TG_MB_C_brd_V02_OCP.brd")
		(comment 1 "Grand Teton / footprints 396-397 of 8354")
	)
	(layers
		(0 "F.Cu" signal "TOP")
		(4 "In1.Cu" signal "GND")
		(6 "In2.Cu" signal "IN1")
		(8 "In3.Cu" signal "GND1")
		(10 "In4.Cu" signal "IN2")
		(12 "In5.Cu" signal "GND2")
		(14 "In6.Cu" signal "IN3")
		(16 "In7.Cu" signal "GND3")
		(18 "In8.Cu" signal "VCC")
		(20 "In9.Cu" signal "VCC1")
		(22 "In10.Cu" signal "GND4")
		(24 "In11.Cu" signal "IN4")
		(26 "In12.Cu" signal "GND5")
		(28 "In13.Cu" signal "IN5")
		(30 "In14.Cu" signal "GND6")
		(32 "In15.Cu" signal "IN6")
		(34 "In16.Cu" signal "GND7")
		(2 "B.Cu" signal "BOTTOM")
		(9 "F.Adhes" user "F.Adhesive")
		(11 "B.Adhes" user "B.Adhesive")
		(13 "F.Paste" user "Package Geometry/Pastemask Top")
		(15 "B.Paste" user "Package Geometry/Pastemask Bottom")
		(5 "F.SilkS" user "Ref Des/Silkscreen Top")
		(7 "B.SilkS" user "Ref Des/Silkscreen Bottom")
		(1 "F.Mask" user "Board Geometry/Soldermask Top")
		(3 "B.Mask" user "Board Geometry/Soldermask Bottom")
		(17 "Dwgs.User" user "User.Drawings")
		(19 "Cmts.User" user "User.Comments")
		(21 "Eco1.User" user "User.Eco1")
		(23 "Eco2.User" user "User.Eco2")
		(25 "Edge.Cuts" user "Board Geometry/Outline")
		(27 "Margin" user)
		(31 "F.CrtYd" user "Package Geometry/Place Bound Top")
		(29 "B.CrtYd" user "Package Geometry/Place Bound Bottom")
		(35 "F.Fab" user "Ref Des/Assembly Top")
		(33 "B.Fab" user "Ref Des/Assembly Bottom")
	)
	(footprint ""
		(layer "F.Cu")
		(at 120.396 -421.513 180)
		(property "Reference" "R3465"
			(at 0 0 180)
			(layer "F.SilkS")
			(hide yes)
			(effects
				(font
					(size 1.27 1.27)
				)
			)
		)
		(property "Value" ""
			(at 0 0 180)
			(layer "F.Fab")
			(effects
				(font
					(size 1.27 1.27)
				)
			)
		)
		(duplicate_pad_numbers_are_jumpers no)
		(fp_line
			(start 0.7874 0.4064)
			(end -0.7874 0.4064)
			(stroke
				(width 0.1524)
				(type default)
			)
			(layer "F.SilkS")
		)
		(fp_line
			(start 0.7874 -0.4064)
			(end 0.7874 0.4064)
			(stroke
				(width 0.1524)
				(type default)
			)
			(layer "F.SilkS")
		)
		(fp_line
			(start -0.7874 0.4064)
			(end -0.7874 -0.4064)
			(stroke
				(width 0.1524)
				(type default)
			)
			(layer "F.SilkS")
		)
		(fp_line
			(start -0.7874 -0.4064)
			(end 0.7874 -0.4064)
			(stroke
				(width 0.1524)
				(type default)
			)
			(layer "F.SilkS")
		)
		(fp_line
			(start 0.67945 0.3048)
			(end 0.120396 0.3048)
			(stroke
				(width 0.1)
				(type default)
			)
			(layer "F.Fab")
		)
		(fp_line
			(start 0.67945 -0.3048)
			(end 0.67945 0.3048)
			(stroke
				(width 0.1)
				(type default)
			)
			(layer "F.Fab")
		)
		(fp_line
			(start 0.12065 -0.2794)
			(end 0.12065 -0.3048)
			(stroke
				(width 0.1)
				(type default)
			)
			(layer "F.Fab")
		)
		(fp_line
			(start 0.12065 -0.3048)
			(end 0.67945 -0.3048)
			(stroke
				(width 0.1)
				(type default)
			)
			(layer "F.Fab")
		)
		(fp_line
			(start 0.120396 0.3048)
			(end 0.120396 0.2794)
			(stroke
				(width 0.1)
				(type default)
			)
			(layer "F.Fab")
		)
		(fp_line
			(start 0.120396 0.2794)
			(end -0.12065 0.2794)
			(stroke
				(width 0.1)
				(type default)
			)
			(layer "F.Fab")
		)
		(fp_line
			(start -0.12065 0.3048)
			(end -0.67945 0.3048)
			(stroke
				(width 0.1)
				(type default)
			)
			(layer "F.Fab")
		)
		(fp_line
			(start -0.12065 0.2794)
			(end -0.12065 0.3048)
			(stroke
				(width 0.1)
				(type default)
			)
			(layer "F.Fab")
		)
		(fp_line
			(start -0.12065 -0.2794)
			(end 0.12065 -0.2794)
			(stroke
				(width 0.1)
				(type default)
			)
			(layer "F.Fab")
		)
		(fp_line
			(start -0.12065 -0.305054)
			(end -0.12065 -0.2794)
			(stroke
				(width 0.1)
				(type default)
			)
			(layer "F.Fab")
		)
		(fp_line
			(start -0.67945 0.3048)
			(end -0.67945 -0.305054)
			(stroke
				(width 0.1)
				(type default)
			)
			(layer "F.Fab")
		)
		(fp_line
			(start -0.67945 -0.305054)
			(end -0.12065 -0.305054)
			(stroke
				(width 0.1)
				(type default)
			)
			(layer "F.Fab")
		)
		(pad "1" smd circle
			(at -0.40005 0 180)
			(size 0 0)
			(layers "F.Cu" "F.Mask" "F.Paste")
			(net "P3V3_AUX")
		)
		(pad "2" smd circle
			(at 0.40005 0 180)
			(size 0 0)
			(layers "F.Cu" "F.Mask" "F.Paste")
			(net "GPU_HMC_PRSNT_N")
		)
	)
	(footprint ""
		(layer "F.Cu")
		(at 172.9232 -94.833948 -90)
		(property "Reference" "R6015"
			(at 0 0 270)
			(layer "F.SilkS")
			(hide yes)
			(effects
				(font
					(size 1.27 1.27)
				)
			)
		)
		(property "Value" ""
			(at 0 0 270)
			(layer "F.Fab")
			(effects
				(font
					(size 1.27 1.27)
				)
			)
		)
		(duplicate_pad_numbers_are_jumpers no)
		(fp_line
			(start -0.7874 0.4064)
			(end -0.7874 -0.4064)
			(stroke
				(width 0.1524)
				(type default)
			)
			(layer "F.SilkS")
		)
		(fp_line
			(start 0.7874 0.4064)
			(end -0.7874 0.4064)
			(stroke
				(width 0.1524)
				(type default)
			)
			(layer "F.SilkS")
		)
		(fp_line
			(start -0.7874 -0.4064)
			(end 0.7874 -0.4064)
			(stroke
				(width 0.1524)
				(type default)
			)
			(layer "F.SilkS")
		)
		(fp_line
			(start 0.7874 -0.4064)
			(end 0.7874 0.4064)
			(stroke
				(width 0.1524)
				(type default)
			)
			(layer "F.SilkS")
		)
		(fp_line
			(start -0.67945 0.3048)
			(end -0.67945 -0.305054)
			(stroke
				(width 0.1)
				(type default)
			)
			(layer "F.Fab")
		)
		(fp_line
			(start -0.12065 0.3048)
			(end -0.67945 0.3048)
			(stroke
				(width 0.1)
				(type default)
			)
			(layer "F.Fab")
		)
		(fp_line
			(start 0.120396 0.3048)
			(end 0.120396 0.2794)
			(stroke
				(width 0.1)
				(type default)
			)
			(layer "F.Fab")
		)
		(fp_line
			(start 0.67945 0.3048)
			(end 0.120396 0.3048)
			(stroke
				(width 0.1)
				(type default)
			)
			(layer "F.Fab")
		)
		(fp_line
			(start -0.12065 0.2794)
			(end -0.12065 0.3048)
			(stroke
				(width 0.1)
				(type default)
			)
			(layer "F.Fab")
		)
		(fp_line
			(start 0.120396 0.2794)
			(end -0.12065 0.2794)
			(stroke
				(width 0.1)
				(type default)
			)
			(layer "F.Fab")
		)
		(fp_line
			(start -0.12065 -0.2794)
			(end 0.12065 -0.2794)
			(stroke
				(width 0.1)
				(type default)
			)
			(layer "F.Fab")
		)
		(fp_line
			(start 0.12065 -0.2794)
			(end 0.12065 -0.3048)
			(stroke
				(width 0.1)
				(type default)
			)
			(layer "F.Fab")
		)
		(fp_line
			(start 0.12065 -0.3048)
			(end 0.67945 -0.3048)
			(stroke
				(width 0.1)
				(type default)
			)
			(layer "F.Fab")
		)
		(fp_line
			(start 0.67945 -0.3048)
			(end 0.67945 0.3048)
			(stroke
				(width 0.1)
				(type default)
			)
			(layer "F.Fab")
		)
		(fp_line
			(start -0.67945 -0.305054)
			(end -0.12065 -0.305054)
			(stroke
				(width 0.1)
				(type default)
			)
			(layer "F.Fab")
		)
		(fp_line
			(start -0.12065 -0.305054)
			(end -0.12065 -0.2794)
			(stroke
				(width 0.1)
				(type default)
			)
			(layer "F.Fab")
		)
		(pad "1" smd circle
			(at -0.40005 0 270)
			(size 0 0)
			(layers "F.Cu" "F.Mask" "F.Paste")
			(net "SGPIO_SCM_LD_<1>")
		)
		(pad "2" smd circle
			(at 0.40005 0 270)
			(size 0 0)
			(layers "F.Cu" "F.Mask" "F.Paste")
			(net "SGPIO_SCM_LD_R_<1>")
		)
	)
)
